G04 ================== begin FILE IDENTIFICATION RECORD ==================*
G04 Layout Name:  16368-sb.brd*
G04 Film Name:    L4*
G04 File Format:  Gerber RS274X*
G04 File Origin:  Cadence Allegro 16.5-S056*
G04 Origin Date:  Tue Feb 07 09:07:44 2017*
G04 *
G04 Layer:  VIA CLASS/L4*
G04 Layer:  PIN/L4*
G04 Layer:  ETCH/L4*
G04 Layer:  DRAWING FORMAT/LAYER_PCB_STORY*
G04 Layer:  DRAWING FORMAT/LAYER_L4*
G04 *
G04 Offset:    (0.00 0.00)*
G04 Mirror:    No*
G04 Mode:      Positive*
G04 Rotation:  0*
G04 FullContactRelief:  No*
G04 UndefLineWidth:     6.00*
G04 ================== end FILE IDENTIFICATION RECORD ====================*
%FSLAX35Y35*MOIN*%
%IR0*IPPOS*OFA0.00000B0.00000*MIA0B0*SFA1.00000B1.00000*%
%ADD12C,.02*%
%ADD13C,.022*%
%ADD11C,.042*%
%ADD10C,.034*%
%ADD14C,.005*%
%ADD15C,.006*%
%ADD16C,.008*%
%ADD19C,.04404*%
%ADD20C,.04604*%
%ADD18C,.06404*%
%ADD17C,.11004*%
G75*
%LPD*%
G75*
G36*
G01X3937Y3001D02*
G02X3001Y3937I0J936D01*
G01Y57874D01*
G02X3937Y58810I936J0D01*
G01X30031D01*
G02X30265Y58086I0J-400D01*
G03X29471Y57266I1940J-2672D01*
G02X29205Y57205I-166J112D01*
G03X29309Y53460I-1105J-1905D01*
G02X29578Y53414I110J-167D01*
G03X34145Y58086I2627J2000D01*
G02X34379Y58810I234J324D01*
G01X36190D01*
X37500Y57500D01*
Y55000D01*
X32000Y49500D01*
X25500D01*
X24000Y48000D01*
Y46000D01*
X26000Y44000D01*
X35000D01*
X37000Y42000D01*
Y34500D01*
X43500Y28000D01*
Y24500D01*
X45000Y23000D01*
X47000D01*
X53000Y29000D01*
X59000D01*
X71798Y41798D01*
X86102D01*
X86900Y41000D01*
X91500D01*
X101000Y31500D01*
X120500D01*
X123500Y34500D01*
X128500D01*
X130000Y36000D01*
Y38000D01*
X128500Y39500D01*
X115000D01*
X113600Y40900D01*
X113589Y40915D01*
G03X113259Y41294I-1891J-1313D01*
G01X102000Y52553D01*
Y55500D01*
X103500Y57000D01*
X119500D01*
X126600Y49900D01*
X128400D01*
X130000Y51500D01*
Y57000D01*
X131810Y58810D01*
X173228D01*
G02X174164Y57874I0J-936D01*
G01Y3937D01*
G02X173228Y3001I-936J0D01*
G01X3937D01*
G37*
%LPC*%
G75*
G36*
G01X29643Y40871D02*
G03X29922Y40869I141J142D01*
G02X29183Y37154I2283J-2385D01*
G03X28925Y37258I-183J-81D01*
G02X29643Y40871I-825J2042D01*
G37*
G36*
G01X54642Y19444D02*
G03X54358I-142J-141D01*
G02Y22556I-1558J1556D01*
G03X54642I142J141D01*
G02Y19444I1558J-1556D01*
G37*
G36*
G01X67992Y23408D02*
X70408D01*
X71500Y24500D01*
Y36500D01*
X75000Y40000D01*
X77000D01*
X78500Y38500D01*
Y25000D01*
X80000Y23500D01*
X88000D01*
X92500Y28000D01*
X99000D01*
X102000Y25000D01*
X127500D01*
X136000Y16500D01*
Y15000D01*
X134500Y13500D01*
X133590D01*
G02X133410I-90J2200D01*
G01X132500D01*
X128500Y17500D01*
X117500D01*
X116500Y18500D01*
X91000D01*
X83000Y10500D01*
X81590D01*
G02X81410I-90J2200D01*
G01X80500D01*
X78800Y12200D01*
X72277D01*
X72275Y12198D01*
X70198D01*
X69500Y11500D01*
X52500D01*
X51000Y13000D01*
Y15000D01*
X52500Y16500D01*
X61000D01*
X63000Y18500D01*
Y25500D01*
X64500Y27000D01*
X66000D01*
X67500Y25500D01*
Y24527D01*
G02Y24347I-2200J-90D01*
G01Y23900D01*
X67992Y23408D01*
G37*
G36*
G01X156337Y9917D02*
G03X155832Y9423I-121J-381D01*
G02X152370Y11421I-2783J-823D01*
G03X152546Y12106I-93J389D01*
G02X151870Y12782I6903J7579D01*
G03X151185Y12606I-296J-269D01*
G02X149187Y16068I-2821J679D01*
G03X149681Y16573I113J384D01*
G02Y22797I9768J3112D01*
G03X149187Y23302I-381J121D01*
G02X151185Y26764I-823J2783D01*
G03X151870Y26588I389J93D01*
G02X152546Y27264I7579J-6903D01*
G03X152370Y27949I-269J296D01*
G02X155832Y29947I679J2821D01*
G03X156337Y29453I384J-113D01*
G02X162561I3112J-9768D01*
G03X163066Y29947I121J381D01*
G02X166528Y27949I2783J823D01*
G03X166352Y27264I93J-389D01*
G02X167028Y26588I-6903J-7579D01*
G03X167713Y26764I296J269D01*
G02X169711Y23302I2821J-679D01*
G03X169217Y22797I-113J-384D01*
G02Y16573I-9768J-3112D01*
G03X169711Y16068I381J-121D01*
G02X167713Y12606I823J-2783D01*
G03X167028Y12782I-389J-93D01*
G02X166352Y12106I-7579J6903D01*
G03X166528Y11421I269J-296D01*
G02X163066Y9423I-679J-2821D01*
G03X162561Y9917I-384J113D01*
G02X156337I-3112J9768D01*
G37*
G36*
G01X24620Y12106D02*
G03X24796Y11421I269J-296D01*
G02X21334Y9423I-679J-2821D01*
G03X20829Y9917I-384J113D01*
G02X14605I-3112J9768D01*
G03X14100Y9423I-121J-381D01*
G02X10638Y11421I-2783J-823D01*
G03X10814Y12106I-93J389D01*
G02X10138Y12782I6903J7579D01*
G03X9453Y12606I-296J-269D01*
G02X7455Y16068I-2821J679D01*
G03X7949Y16573I113J384D01*
G02Y22797I9768J3112D01*
G03X7455Y23302I-381J121D01*
G02X9453Y26764I-823J2783D01*
G03X10138Y26588I389J93D01*
G02X10814Y27264I7579J-6903D01*
G03X10638Y27949I-269J296D01*
G02X14100Y29947I679J2821D01*
G03X14605Y29453I384J-113D01*
G02X20829I3112J-9768D01*
G03X21334Y29947I121J381D01*
G02X24796Y27949I2783J823D01*
G03X24620Y27264I93J-389D01*
G02X25296Y26588I-6903J-7579D01*
G03X25981Y26764I296J269D01*
G02X27979Y23302I2821J-679D01*
G03X27485Y22797I-113J-384D01*
G02Y16573I-9768J-3112D01*
G03X27979Y16068I381J-121D01*
G02X25981Y12606I823J-2783D01*
G03X25296Y12782I-389J-93D01*
G02X24620Y12106I-7579J6903D01*
G37*
G36*
G01X133656Y6866D02*
G03X133164Y6405I-99J-388D01*
G02X131544Y8134I-2164J-405D01*
G03X132036Y8595I99J388D01*
G02X133656Y6866I2164J405D01*
G37*
G54D19*
X109000Y11000D03*
X95400Y12500D03*
X84700Y26702D03*
X54500Y25500D03*
G54D20*
X111800Y52264D03*
G54D18*
X127264Y43898D03*
G54D17*
X9000Y48000D03*
X164500Y48500D03*
%LPD*%
G75*
G54D10*
X28802Y13285D03*
X24117Y8600D03*
X11317D03*
X6632Y13285D03*
Y26085D03*
X11317Y30770D03*
X24117D03*
X28802Y26085D03*
X170534Y13285D03*
X165849Y8600D03*
X153049D03*
X148364Y13285D03*
Y26085D03*
X153049Y30770D03*
X165849D03*
X170534Y26085D03*
G54D11*
X32205Y38484D03*
Y55414D03*
G54D12*
G01X-149983Y-76117D02*
Y-156117D01*
G01D02*
X864117D01*
G01X-153983Y-60117D02*
G02I-12000J0D01*
G01X-159133D02*
G02I-6850J0D01*
G01X-165983Y-76117D02*
Y-44117D01*
G01X-149983Y-60117D02*
X-181983D01*
G01X-149983Y-76117D02*
X864117D01*
G01X-149983Y-111617D02*
X864117D01*
G01X28802Y22983D02*
Y26085D01*
G01D02*
Y29187D01*
G01Y26085D02*
X31904D01*
G01X24117Y30770D02*
Y33872D01*
G01X21015Y30770D02*
X24117D01*
G01D02*
X27219D01*
G01X11317D02*
Y33872D01*
G01X8215Y30770D02*
X11317D01*
G01D02*
X14419D01*
G01X6632Y22983D02*
Y26085D01*
G01D02*
Y29187D01*
G01Y10183D02*
Y13285D01*
G01D02*
Y16387D01*
G01X11317Y5498D02*
Y8600D01*
G01X8215D02*
X11317D01*
G01D02*
X14419D01*
G01X24117Y5498D02*
Y8600D01*
G01X21015D02*
X24117D01*
G01D02*
X27219D01*
G01X28802Y10183D02*
Y13285D01*
G01D02*
Y16387D01*
G01Y13285D02*
X31904D01*
G01X32205Y51912D02*
Y55414D01*
G01D02*
X35707D01*
G01X32205Y34982D02*
Y38484D01*
G01D02*
Y41986D01*
G01Y38484D02*
X35707D01*
G01X76617Y-76117D02*
Y-156117D01*
G01X170534Y22983D02*
Y26085D01*
G01D02*
Y29187D01*
G01X165849Y30770D02*
Y33872D01*
G01X162747Y30770D02*
X165849D01*
G01D02*
X168951D01*
G01X153049D02*
Y33872D01*
G01X149947Y30770D02*
X153049D01*
G01D02*
X156151D01*
G01X148364Y22983D02*
Y26085D01*
G01D02*
Y29187D01*
G01X145262Y26085D02*
X148364D01*
G01Y10183D02*
Y13285D01*
G01D02*
Y16387D01*
G01X145262Y13285D02*
X148364D01*
G01X153049Y5498D02*
Y8600D01*
G01X149947D02*
X153049D01*
G01D02*
X156151D01*
G01X165849Y5498D02*
Y8600D01*
G01X162747D02*
X165849D01*
G01D02*
X168951D01*
G01X170534Y10183D02*
Y13285D01*
G01D02*
Y16387D01*
G01X214117Y-76117D02*
Y-156117D01*
G01X329117Y-76117D02*
Y-156117D01*
G01X496617Y-76117D02*
Y-156117D01*
G01X666617Y-76117D02*
Y-156117D01*
G01X864117Y-76117D02*
Y-156117D01*
G01X892117Y-60117D02*
G02I-12000J0D01*
G01X886967D02*
G02I-6850J0D01*
G01X880117Y-76117D02*
Y-44117D01*
G01X896117Y-60117D02*
X864117D01*
X34200Y47000D03*
X20000Y55000D03*
X15000Y45000D03*
X5000Y38000D03*
Y55000D03*
X68750Y24100D03*
X79940Y26850D03*
X70700Y11200D03*
X40100Y21692D03*
X35000Y5000D03*
X41200Y7400D03*
X98200Y16500D03*
X108140Y28132D03*
X53437Y13900D03*
X71405Y19607D03*
X68500Y13800D03*
X98000Y25500D03*
X69000Y17200D03*
X65800Y21000D03*
X45250Y35850D03*
X36733Y47067D03*
X44607Y46831D03*
X52218Y47067D03*
X56000Y55500D03*
X39300Y35500D03*
X49730Y46821D03*
X103655Y52264D03*
X88940Y39400D03*
X76000Y37750D03*
X87700Y43400D03*
X119400Y29800D03*
X143000Y5000D03*
X137000Y12750D03*
X133500Y15700D03*
X119500Y33900D03*
X170000Y45000D03*
X135500D03*
X155000D03*
X165000Y55000D03*
X145000D03*
Y36500D03*
X119403Y52264D03*
G54D13*
X46000Y25600D03*
X96000Y55600D03*
X111700Y39600D03*
X127500Y52264D03*
Y37000D03*
G54D14*
G01X45250Y35850D02*
X36733Y44367D01*
Y47067D01*
G01D02*
Y48197D01*
X40836Y52300D01*
X56300D01*
X62561Y58561D01*
X121203D01*
X127500Y52264D01*
G01X96000Y55600D02*
X63136D01*
X57336Y49800D01*
X46300D01*
X44607Y48107D01*
Y46831D01*
G01X111700Y39600D02*
Y40800D01*
X100900Y51600D01*
X90500D01*
X89950Y51050D01*
X67750D01*
X60800Y44100D01*
X53900D01*
X52230Y45770D01*
Y46537D01*
X52218Y46549D01*
Y47067D01*
G01X56000Y55500D02*
X53000Y58500D01*
X43500D01*
X34200Y49200D01*
Y47000D01*
G01X39300Y35500D02*
X41400Y33400D01*
X57172D01*
X69822Y46050D01*
X88549D01*
X100699Y33900D01*
X119500D01*
G01X49730Y46821D02*
Y44734D01*
X52864Y41600D01*
X61836D01*
X68786Y48550D01*
X89585D01*
X99135Y39000D01*
X105000D01*
X107000Y37000D01*
X127500D01*
G54D15*
G01X-137600Y-128617D02*
Y-146117D01*
X-128866D01*
G01X-113987Y-136784D02*
X-113113Y-135909D01*
X-112458Y-134451D01*
X-112021Y-132408D01*
X-112458Y-130659D01*
X-113331Y-129492D01*
X-114860Y-128617D01*
X-120755D01*
Y-146117D01*
X-113550D01*
X-112021Y-144951D01*
X-111148Y-143200D01*
X-110711Y-141159D01*
X-111148Y-139117D01*
X-112458Y-137367D01*
X-113987Y-136784D01*
X-120755D01*
G01X-93430Y-130076D02*
X-94740Y-129200D01*
X-96268Y-128617D01*
X-98015D01*
X-99980Y-129492D01*
X-101508Y-130950D01*
X-102600Y-132701D01*
X-103473Y-135617D01*
X-103692Y-138242D01*
X-103255Y-140867D01*
X-102600Y-142617D01*
X-101290Y-144367D01*
X-99761Y-145534D01*
X-98233Y-146117D01*
X-96705D01*
X-95176Y-145534D01*
X-93866Y-144659D01*
X-92774Y-143493D01*
G01X-67600Y-128617D02*
Y-146117D01*
X-58866D01*
G01X-41366D02*
X-50100D01*
Y-128617D01*
X-41366D01*
G01X-44860Y-137075D02*
X-50100D01*
G01X-33036Y-146117D02*
Y-128617D01*
X-28670D01*
X-26923Y-129492D01*
X-25613Y-130659D01*
X-24521Y-132408D01*
X-23648Y-134451D01*
X-23430Y-137367D01*
X-23648Y-140284D01*
X-24521Y-142326D01*
X-25613Y-144076D01*
X-26923Y-145242D01*
X-28670Y-146117D01*
X-33036D01*
G01X10260Y-135909D02*
X8732Y-134742D01*
X7422Y-134451D01*
X5675Y-135034D01*
X4365Y-136200D01*
X3492Y-138242D01*
X3273Y-140284D01*
X3492Y-142326D01*
X4365Y-144076D01*
X5675Y-145534D01*
X7422Y-146117D01*
X8950Y-145534D01*
X10260Y-144367D01*
G01X28197Y-146117D02*
Y-134451D01*
G01Y-136492D02*
X27324Y-135326D01*
X26013Y-134742D01*
X24485Y-134451D01*
X22957Y-135034D01*
X21647Y-136200D01*
X20773Y-137950D01*
X20337Y-140284D01*
X20773Y-142617D01*
X21647Y-144367D01*
X22957Y-145534D01*
X24485Y-146117D01*
X26013Y-145825D01*
X27324Y-144951D01*
X28197Y-143784D01*
G01X38710Y-146117D02*
Y-134451D01*
G01Y-136784D02*
X39802Y-135617D01*
X40894Y-134742D01*
X42422Y-134451D01*
X43513Y-134742D01*
X44824Y-135617D01*
G01X63197Y-128617D02*
Y-146117D01*
G01Y-143493D02*
X62324Y-144951D01*
X61013Y-145825D01*
X59485Y-146117D01*
X57739Y-145534D01*
X56429Y-144076D01*
X55555Y-142326D01*
X55337Y-140284D01*
X55555Y-138242D01*
X56429Y-136492D01*
X57739Y-135034D01*
X59485Y-134451D01*
X61013Y-134742D01*
X62105Y-135326D01*
X63197Y-136492D01*
G01X-77660Y-101117D02*
Y-83617D01*
X-71983Y-98200D01*
X-66306Y-83617D01*
Y-101117D01*
G01X-54483D02*
X-55793Y-100825D01*
X-57103Y-99659D01*
X-57977Y-97617D01*
X-58413Y-95284D01*
X-57977Y-92950D01*
X-57103Y-90909D01*
X-55793Y-89742D01*
X-54483Y-89451D01*
X-53173Y-89742D01*
X-51863Y-90909D01*
X-50990Y-92950D01*
X-50771Y-95284D01*
X-50990Y-97617D01*
X-51863Y-99659D01*
X-53173Y-100825D01*
X-54483Y-101117D01*
G01X-33053Y-83617D02*
Y-101117D01*
G01Y-98493D02*
X-33926Y-99951D01*
X-35237Y-100825D01*
X-36765Y-101117D01*
X-38511Y-100534D01*
X-39821Y-99076D01*
X-40695Y-97326D01*
X-40913Y-95284D01*
X-40695Y-93242D01*
X-39821Y-91492D01*
X-38511Y-90034D01*
X-36765Y-89451D01*
X-35237Y-89742D01*
X-34145Y-90326D01*
X-33053Y-91492D01*
G01X-22758Y-93242D02*
X-15771D01*
X-16426Y-91200D01*
X-17518Y-90034D01*
X-19046Y-89451D01*
X-20575Y-89742D01*
X-21885Y-90617D01*
X-22758Y-92659D01*
X-23195Y-94409D01*
Y-96159D01*
X-22758Y-97909D01*
X-21666Y-99659D01*
X-20356Y-100825D01*
X-18828Y-101117D01*
X-17300Y-100534D01*
X-15771Y-98784D01*
G01X-1983Y-101117D02*
Y-83617D01*
G01X110317Y-146117D02*
Y-128617D01*
X107697Y-132117D01*
G01Y-146117D02*
X112937D01*
G01X123669Y-138826D02*
X125197Y-136784D01*
X126507Y-135617D01*
X128254Y-135034D01*
X129782Y-135617D01*
X130874Y-136784D01*
X131747Y-138534D01*
X131965Y-140575D01*
X131747Y-142326D01*
X130874Y-144076D01*
X129563Y-145534D01*
X128035Y-146117D01*
X126289Y-145534D01*
X124760Y-143784D01*
X123887Y-141159D01*
X123669Y-138242D01*
X124105Y-134451D01*
X124760Y-132408D01*
X125852Y-130367D01*
X127380Y-128909D01*
X128909Y-128617D01*
X130437Y-129200D01*
X131529Y-130659D01*
G01X140514Y-142617D02*
X141823Y-144659D01*
X143570Y-145825D01*
X145535Y-146117D01*
X147282Y-145825D01*
X149029Y-144367D01*
X150120Y-142617D01*
X150339Y-140867D01*
X149902Y-138826D01*
X148374Y-137367D01*
X146845Y-136784D01*
X144880D01*
G01X146845D02*
X148155Y-135909D01*
X149247Y-134451D01*
X149684Y-132701D01*
X149247Y-130950D01*
X148155Y-129492D01*
X146190Y-128617D01*
X144225Y-128909D01*
X142260Y-130076D01*
G01X158669Y-138826D02*
X160197Y-136784D01*
X161507Y-135617D01*
X163254Y-135034D01*
X164782Y-135617D01*
X165874Y-136784D01*
X166747Y-138534D01*
X166965Y-140575D01*
X166747Y-142326D01*
X165874Y-144076D01*
X164563Y-145534D01*
X163035Y-146117D01*
X161289Y-145534D01*
X159760Y-143784D01*
X158887Y-141159D01*
X158669Y-138242D01*
X159105Y-134451D01*
X159760Y-132408D01*
X160852Y-130367D01*
X162380Y-128909D01*
X163909Y-128617D01*
X165437Y-129200D01*
X166529Y-130659D01*
G01X180317Y-146117D02*
X181845Y-145825D01*
X183592Y-144951D01*
X184684Y-143493D01*
X185120Y-141450D01*
X184684Y-139409D01*
X183374Y-137659D01*
X181409Y-136784D01*
X179225D01*
X177915Y-136200D01*
X176823Y-134742D01*
X176387Y-132701D01*
X177042Y-130659D01*
X178570Y-129200D01*
X180317Y-128617D01*
X182063Y-129200D01*
X183592Y-130659D01*
X184247Y-132701D01*
X183810Y-134742D01*
X182719Y-136200D01*
X181409Y-136784D01*
X179225D01*
X177260Y-137659D01*
X175950Y-139409D01*
X175514Y-141450D01*
X175950Y-143493D01*
X177042Y-144951D01*
X178789Y-145825D01*
X180317Y-146117D01*
G01X97200Y-101117D02*
Y-83617D01*
X102440D01*
X104187Y-84492D01*
X105497Y-86534D01*
X105934Y-88867D01*
X105497Y-91200D01*
X104405Y-92950D01*
X102440Y-93826D01*
X97200D01*
G01X123870Y-85076D02*
X122560Y-84200D01*
X121032Y-83617D01*
X119285D01*
X117320Y-84492D01*
X115792Y-85950D01*
X114700Y-87701D01*
X113827Y-90617D01*
X113608Y-93242D01*
X114045Y-95867D01*
X114700Y-97617D01*
X116010Y-99367D01*
X117539Y-100534D01*
X119067Y-101117D01*
X120595D01*
X122124Y-100534D01*
X123434Y-99659D01*
X124526Y-98493D01*
G01X138313Y-91784D02*
X139187Y-90909D01*
X139842Y-89451D01*
X140279Y-87408D01*
X139842Y-85659D01*
X138969Y-84492D01*
X137440Y-83617D01*
X131545D01*
Y-101117D01*
X138750D01*
X140279Y-99951D01*
X141152Y-98200D01*
X141589Y-96159D01*
X141152Y-94117D01*
X139842Y-92367D01*
X138313Y-91784D01*
X131545D01*
G01X147517Y-106950D02*
X160617D01*
G01X166545Y-101117D02*
Y-83617D01*
X176589Y-101117D01*
Y-83617D01*
G01X189067Y-101117D02*
X187320Y-100825D01*
X185792Y-99659D01*
X184482Y-97909D01*
X183608Y-95867D01*
X183172Y-93534D01*
Y-91200D01*
X183608Y-88867D01*
X184482Y-86825D01*
X185792Y-85076D01*
X187320Y-83909D01*
X189067Y-83617D01*
X190813Y-83909D01*
X192342Y-85076D01*
X193652Y-86825D01*
X194526Y-88867D01*
X194962Y-91200D01*
Y-93534D01*
X194526Y-95867D01*
X193652Y-97909D01*
X192342Y-99659D01*
X190813Y-100825D01*
X189067Y-101117D01*
G01X258282Y-143784D02*
X260029Y-145242D01*
X261994Y-146117D01*
X263740D01*
X265487Y-145242D01*
X266797Y-143784D01*
X267452Y-141742D01*
X267015Y-139701D01*
X265924Y-137950D01*
X263959Y-136784D01*
X261339Y-136200D01*
X259810Y-135034D01*
X259155Y-132992D01*
X259592Y-130950D01*
X260684Y-129492D01*
X262212Y-128617D01*
X263740D01*
X265269Y-129200D01*
X266579Y-130659D01*
G01X282113Y-136784D02*
X282987Y-135909D01*
X283642Y-134451D01*
X284079Y-132408D01*
X283642Y-130659D01*
X282769Y-129492D01*
X281240Y-128617D01*
X275345D01*
Y-146117D01*
X282550D01*
X284079Y-144951D01*
X284952Y-143200D01*
X285389Y-141159D01*
X284952Y-139117D01*
X283642Y-137367D01*
X282113Y-136784D01*
X275345D01*
G01X239908Y-83617D02*
X245367Y-101117D01*
X250826Y-83617D01*
G01X267234Y-101117D02*
X258500D01*
Y-83617D01*
X267234D01*
G01X263740Y-92075D02*
X258500D01*
G01X276000Y-101117D02*
Y-83617D01*
X281459D01*
X283205Y-84492D01*
X284297Y-85659D01*
X284734Y-87992D01*
X284297Y-90326D01*
X282987Y-91784D01*
X281459Y-92659D01*
X276000D01*
G01X281459D02*
X284734Y-101117D01*
G01X297867Y-101700D02*
X297430Y-101409D01*
Y-100825D01*
X297867Y-100534D01*
X298304Y-100825D01*
Y-101409D01*
X297867Y-101700D01*
G01X425934Y-128617D02*
Y-146117D01*
X417200D01*
G01X401447D02*
Y-128617D01*
X409526Y-141159D01*
X398608D01*
G01X373450Y-83617D02*
Y-101117D01*
X382184D01*
G01X399247D02*
Y-89451D01*
G01Y-91492D02*
X398374Y-90326D01*
X397063Y-89742D01*
X395535Y-89451D01*
X394007Y-90034D01*
X392697Y-91200D01*
X391823Y-92950D01*
X391387Y-95284D01*
X391823Y-97617D01*
X392697Y-99367D01*
X394007Y-100534D01*
X395535Y-101117D01*
X397063Y-100825D01*
X398374Y-99951D01*
X399247Y-98784D01*
G01X408232Y-106367D02*
X409542Y-106950D01*
X411289Y-106367D01*
X412380Y-105201D01*
X413254Y-103742D01*
X414563Y-99076D01*
X417402Y-89451D01*
G01X410415D02*
X414563Y-99076D01*
G01X427042Y-93242D02*
X434029D01*
X433374Y-91200D01*
X432282Y-90034D01*
X430754Y-89451D01*
X429225Y-89742D01*
X427915Y-90617D01*
X427042Y-92659D01*
X426605Y-94409D01*
Y-96159D01*
X427042Y-97909D01*
X428134Y-99659D01*
X429444Y-100825D01*
X430972Y-101117D01*
X432500Y-100534D01*
X434029Y-98784D01*
G01X444760Y-101117D02*
Y-89451D01*
G01Y-91784D02*
X445852Y-90617D01*
X446944Y-89742D01*
X448472Y-89451D01*
X449563Y-89742D01*
X450874Y-90617D01*
G01X515564Y-101117D02*
Y-83617D01*
X519930D01*
X521677Y-84492D01*
X522987Y-85659D01*
X524079Y-87408D01*
X524952Y-89451D01*
X525170Y-92367D01*
X524952Y-95284D01*
X524079Y-97326D01*
X522987Y-99076D01*
X521677Y-100242D01*
X519930Y-101117D01*
X515564D01*
G01X534592Y-93242D02*
X541579D01*
X540924Y-91200D01*
X539832Y-90034D01*
X538304Y-89451D01*
X536775Y-89742D01*
X535465Y-90617D01*
X534592Y-92659D01*
X534155Y-94409D01*
Y-96159D01*
X534592Y-97909D01*
X535684Y-99659D01*
X536994Y-100825D01*
X538522Y-101117D01*
X540050Y-100534D01*
X541579Y-98784D01*
G01X552092Y-99076D02*
X553184Y-100242D01*
X554712Y-101117D01*
X556022D01*
X557332Y-100534D01*
X558205Y-99659D01*
X558642Y-98493D01*
X558424Y-96742D01*
X557550Y-95867D01*
X553620Y-94117D01*
X552747Y-92075D01*
X553184Y-90617D01*
X554057Y-89742D01*
X555367Y-89451D01*
X556677Y-89742D01*
X557987Y-90617D01*
G01X572867Y-89451D02*
Y-101117D01*
G01Y-84784D02*
X572430Y-84492D01*
Y-83909D01*
X572867Y-83617D01*
X573304Y-83909D01*
Y-84492D01*
X572867Y-84784D01*
G01X587310Y-105492D02*
X588839Y-106659D01*
X590585Y-106950D01*
X592113Y-106659D01*
X593424Y-105201D01*
X594297Y-103159D01*
Y-89451D01*
G01Y-91784D02*
X593424Y-90617D01*
X592113Y-89742D01*
X590585Y-89451D01*
X588839Y-90034D01*
X587747Y-91200D01*
X586873Y-93242D01*
X586437Y-95284D01*
X586655Y-97034D01*
X587529Y-99076D01*
X588839Y-100534D01*
X590585Y-101117D01*
X591895Y-100825D01*
X593424Y-99659D01*
X594297Y-98493D01*
G01X604155Y-101117D02*
Y-89451D01*
G01Y-92367D02*
X605029Y-90909D01*
X606339Y-89742D01*
X608085Y-89451D01*
X609613Y-89742D01*
X610924Y-90909D01*
X611579Y-92950D01*
Y-101117D01*
G01X622092Y-93242D02*
X629079D01*
X628424Y-91200D01*
X627332Y-90034D01*
X625804Y-89451D01*
X624275Y-89742D01*
X622965Y-90617D01*
X622092Y-92659D01*
X621655Y-94409D01*
Y-96159D01*
X622092Y-97909D01*
X623184Y-99659D01*
X624494Y-100825D01*
X626022Y-101117D01*
X627550Y-100534D01*
X629079Y-98784D01*
G01X639810Y-101117D02*
Y-89451D01*
G01Y-91784D02*
X640902Y-90617D01*
X641994Y-89742D01*
X643522Y-89451D01*
X644613Y-89742D01*
X645924Y-90617D01*
G01X559969Y-128617D02*
X568265D01*
X559969Y-146117D01*
X568265D01*
G01X581617D02*
X579870Y-145825D01*
X578342Y-144659D01*
X577032Y-142909D01*
X576158Y-140867D01*
X575722Y-138534D01*
Y-136200D01*
X576158Y-133867D01*
X577032Y-131825D01*
X578342Y-130076D01*
X579870Y-128909D01*
X581617Y-128617D01*
X583363Y-128909D01*
X584892Y-130076D01*
X586202Y-131825D01*
X587076Y-133867D01*
X587512Y-136200D01*
Y-138534D01*
X587076Y-140867D01*
X586202Y-142909D01*
X584892Y-144659D01*
X583363Y-145825D01*
X581617Y-146117D01*
G01X603484D02*
X594750D01*
Y-128617D01*
X603484D01*
G01X599990Y-137075D02*
X594750D01*
G01X686567Y-128617D02*
X684820Y-129200D01*
X683510Y-130659D01*
X682637Y-132408D01*
X681982Y-134742D01*
X681764Y-137367D01*
X681982Y-139992D01*
X682637Y-142326D01*
X683510Y-144076D01*
X684820Y-145534D01*
X686567Y-146117D01*
X688313Y-145534D01*
X689624Y-144076D01*
X690497Y-142326D01*
X691152Y-139992D01*
X691370Y-137367D01*
X691152Y-134742D01*
X690497Y-132408D01*
X689624Y-130659D01*
X688313Y-129200D01*
X686567Y-128617D01*
G01X699919Y-131534D02*
X701229Y-129784D01*
X702757Y-128909D01*
X704504Y-128617D01*
X706687Y-129200D01*
X708215Y-130659D01*
X708652Y-132408D01*
X708434Y-134159D01*
X707560Y-135617D01*
X703194Y-138534D01*
X701229Y-140575D01*
X699919Y-143493D01*
X699482Y-146117D01*
X708652D01*
G01X717637Y-146700D02*
X725497Y-128617D01*
G01X739067D02*
X737320Y-129200D01*
X736010Y-130659D01*
X735137Y-132408D01*
X734482Y-134742D01*
X734264Y-137367D01*
X734482Y-139992D01*
X735137Y-142326D01*
X736010Y-144076D01*
X737320Y-145534D01*
X739067Y-146117D01*
X740813Y-145534D01*
X742124Y-144076D01*
X742997Y-142326D01*
X743652Y-139992D01*
X743870Y-137367D01*
X743652Y-134742D01*
X742997Y-132408D01*
X742124Y-130659D01*
X740813Y-129200D01*
X739067Y-128617D01*
G01X756130Y-146117D02*
X756567Y-142326D01*
X757222Y-139117D01*
X758095Y-136200D01*
X759187Y-132992D01*
X760934Y-128617D01*
X752200D01*
G01X770137Y-146700D02*
X777997Y-128617D01*
G01X787419Y-131534D02*
X788729Y-129784D01*
X790257Y-128909D01*
X792004Y-128617D01*
X794187Y-129200D01*
X795715Y-130659D01*
X796152Y-132408D01*
X795934Y-134159D01*
X795060Y-135617D01*
X790694Y-138534D01*
X788729Y-140575D01*
X787419Y-143493D01*
X786982Y-146117D01*
X796152D01*
G01X809067Y-128617D02*
X807320Y-129200D01*
X806010Y-130659D01*
X805137Y-132408D01*
X804482Y-134742D01*
X804264Y-137367D01*
X804482Y-139992D01*
X805137Y-142326D01*
X806010Y-144076D01*
X807320Y-145534D01*
X809067Y-146117D01*
X810813Y-145534D01*
X812124Y-144076D01*
X812997Y-142326D01*
X813652Y-139992D01*
X813870Y-137367D01*
X813652Y-134742D01*
X812997Y-132408D01*
X812124Y-130659D01*
X810813Y-129200D01*
X809067Y-128617D01*
G01X826567Y-146117D02*
Y-128617D01*
X823947Y-132117D01*
G01Y-146117D02*
X829187D01*
G01X843630D02*
X844067Y-142326D01*
X844722Y-139117D01*
X845595Y-136200D01*
X846687Y-132992D01*
X848434Y-128617D01*
X839700D01*
G01X734264Y-101117D02*
Y-83617D01*
X738630D01*
X740377Y-84492D01*
X741687Y-85659D01*
X742779Y-87408D01*
X743652Y-89451D01*
X743870Y-92367D01*
X743652Y-95284D01*
X742779Y-97326D01*
X741687Y-99076D01*
X740377Y-100242D01*
X738630Y-101117D01*
X734264D01*
G01X760497D02*
Y-89451D01*
G01Y-91492D02*
X759624Y-90326D01*
X758313Y-89742D01*
X756785Y-89451D01*
X755257Y-90034D01*
X753947Y-91200D01*
X753073Y-92950D01*
X752637Y-95284D01*
X753073Y-97617D01*
X753947Y-99367D01*
X755257Y-100534D01*
X756785Y-101117D01*
X758313Y-100825D01*
X759624Y-99951D01*
X760497Y-98784D01*
G01X774067Y-83617D02*
Y-101117D01*
G01X771010Y-89451D02*
X777124D01*
G01X788292Y-93242D02*
X795279D01*
X794624Y-91200D01*
X793532Y-90034D01*
X792004Y-89451D01*
X790475Y-89742D01*
X789165Y-90617D01*
X788292Y-92659D01*
X787855Y-94409D01*
Y-96159D01*
X788292Y-97909D01*
X789384Y-99659D01*
X790694Y-100825D01*
X792222Y-101117D01*
X793750Y-100534D01*
X795279Y-98784D01*
G54D16*
G01X53437Y13900D02*
X61812D01*
X67519Y19607D01*
X71405D01*
G01X133500Y15700D02*
X125900Y23300D01*
X93312D01*
X86912Y16900D01*
X74712D01*
X71612Y13800D01*
X68500D01*
G01X98000Y25500D02*
X92400D01*
X86000Y19100D01*
X73800D01*
X71900Y17200D01*
X69000D01*
G01X76000Y37750D02*
Y26400D01*
X71407Y21807D01*
X66607D01*
X65800Y21000D01*
G01X46000Y25600D02*
X51150Y30750D01*
X58270D01*
X70920Y43400D01*
X87700D01*
M02*
